(kicad_pcb
	(version 20260206)
	(generator "pcbnew")
	(generator_version "10.0")
	(general
		(thickness 1.6)
		(legacy_teardrops no)
	)
	(paper "A4")
	(title_block
		(title "timecard-production-celestica-r4006 — R4006-B0001-02_R01.brd")
		(comment 1 "Time Appliance Project (Time Card) / footprints 181-186 of 1113")
	)
	(layers
		(0 "F.Cu" signal "TOP")
		(4 "In1.Cu" signal "L02_GND1")
		(6 "In2.Cu" signal "L03_SIG1")
		(8 "In3.Cu" signal "L04_GND2")
		(10 "In4.Cu" signal "L05_VCC1")
		(12 "In5.Cu" signal "L06_VCC2")
		(14 "In6.Cu" signal "L07_GND3")
		(16 "In7.Cu" signal "L08_SIG2")
		(18 "In8.Cu" signal "L09_GND4")
		(2 "B.Cu" signal "BOTTOM")
		(9 "F.Adhes" user "F.Adhesive")
		(11 "B.Adhes" user "B.Adhesive")
		(13 "F.Paste" user "Package Geometry/Pastemask Top")
		(15 "B.Paste" user "Package Geometry/Pastemask Bottom")
		(5 "F.SilkS" user "Ref Des/Silkscreen Top")
		(7 "B.SilkS" user "Ref Des/Silkscreen Bottom")
		(1 "F.Mask" user "Board Geometry/Soldermask Top")
		(3 "B.Mask" user "Board Geometry/Soldermask Bottom")
		(17 "Dwgs.User" user "User.Drawings")
		(19 "Cmts.User" user "User.Comments")
		(21 "Eco1.User" user "User.Eco1")
		(23 "Eco2.User" user "User.Eco2")
		(25 "Edge.Cuts" user "Board Geometry/Outline")
		(27 "Margin" user)
		(31 "F.CrtYd" user "Package Geometry/Place Bound Top")
		(29 "B.CrtYd" user "Package Geometry/Place Bound Bottom")
		(35 "F.Fab" user "Ref Des/Assembly Top")
		(33 "B.Fab" user "Ref Des/Assembly Bottom")
	)
	(footprint ""
		(layer "F.Cu")
		(at 39.3192 -16.31188 90)
		(property "Reference" "C17"
			(at -3.10388 0.21717 90)
			(unlocked yes)
			(layer "F.SilkS")
			(effects
				(font
					(size 0.7874 0.5842)
					(thickness 0.1524)
				)
			)
		)
		(property "Value" "VAL*"
			(at 0.0762 2.067306 90)
			(unlocked yes)
			(layer "F.Fab")
			(hide yes)
			(effects
				(font
					(size 0.7874 0.5842)
					(thickness 0.1524)
				)
			)
		)
		(property "Tolerance" "TOL*"
			(at 0.0762 3.032506 90)
			(unlocked yes)
			(layer "Cmts.User")
			(hide yes)
			(effects
				(font
					(size 0.7874 0.5842)
					(thickness 0.1524)
				)
			)
		)
		(property "User Part Number" "PARTNUM*"
			(at 0.1016 4.023106 90)
			(unlocked yes)
			(layer "Cmts.User")
			(hide yes)
			(effects
				(font
					(size 0.7874 0.5842)
					(thickness 0.1524)
				)
			)
		)
		(property "Device Type" "CAPACITOR-G105-0B104-CK,0.1UF,A"
			(at 0.0508 1.127506 90)
			(unlocked yes)
			(layer "F.Fab")
			(hide yes)
			(effects
				(font
					(size 0.7874 0.5842)
					(thickness 0.1524)
				)
			)
		)
		(duplicate_pad_numbers_are_jumpers no)
		(fp_line
			(start 1.143 -0.5588)
			(end -1.143 -0.5588)
			(stroke
				(width 0.1)
				(type default)
			)
			(layer "F.SilkS")
		)
		(fp_line
			(start -1.143 -0.5588)
			(end -1.143 0.5588)
			(stroke
				(width 0.1)
				(type default)
			)
			(layer "F.SilkS")
		)
		(fp_line
			(start 1.143 0.5588)
			(end 1.143 -0.5588)
			(stroke
				(width 0.1)
				(type default)
			)
			(layer "F.SilkS")
		)
		(fp_line
			(start -1.143 0.5588)
			(end 1.143 0.5588)
			(stroke
				(width 0.1)
				(type default)
			)
			(layer "F.SilkS")
		)
		(fp_rect
			(start -1.143 -0.5588)
			(end 1.143 0.5588)
			(stroke
				(width 0)
				(type default)
			)
			(fill no)
			(layer "F.CrtYd")
		)
		(fp_line
			(start 0.508 -0.3048)
			(end -0.508 -0.3048)
			(stroke
				(width 0.1)
				(type default)
			)
			(layer "F.Fab")
		)
		(fp_line
			(start -0.508 -0.3048)
			(end -0.508 0.3048)
			(stroke
				(width 0.1)
				(type default)
			)
			(layer "F.Fab")
		)
		(fp_line
			(start 0.508 0.3048)
			(end 0.508 -0.3048)
			(stroke
				(width 0.1)
				(type default)
			)
			(layer "F.Fab")
		)
		(fp_line
			(start -0.508 0.3048)
			(end 0.508 0.3048)
			(stroke
				(width 0.1)
				(type default)
			)
			(layer "F.Fab")
		)
		(pad "1" smd rect
			(at -0.5334 0 90)
			(size 0.7112 0.6096)
			(layers "F.Cu" "F.Mask" "F.Paste")
			(net "XP3R3V_FPGA")
		)
		(pad "2" smd rect
			(at 0.5334 0 90)
			(size 0.7112 0.6096)
			(layers "F.Cu" "F.Mask" "F.Paste")
			(net "SG")
		)
		(zone
			(layer "F.Cu")
			(hatch none 0.5)
			(connect_pads
				(clearance 0)
			)
			(min_thickness 0.25)
			(keepout
				(tracks allowed)
				(vias not_allowed)
				(pads allowed)
				(copperpour not_allowed)
				(footprints allowed)
			)
			(placement
				(enabled no)
				(sheetname "")
			)
			(fill
				(thermal_gap 0.5)
				(thermal_bridge_width 0.5)
				(island_removal_mode 0)
			)
			(polygon
				(pts
					(xy 39.0144 -16.23568) (xy 39.624 -16.23568) (xy 39.624 -16.38808) (xy 39.0144 -16.38808)
				)
			)
		)
	)
	(footprint ""
		(layer "F.Cu")
		(at 16.256 -57.15 -90)
		(property "Reference" "C85"
			(at 2.286 -0.54737 90)
			(unlocked yes)
			(layer "F.SilkS")
			(effects
				(font
					(size 0.7874 0.5842)
					(thickness 0.1524)
				)
			)
		)
		(property "Value" "VAL*"
			(at 0.0762 2.067306 270)
			(unlocked yes)
			(layer "F.Fab")
			(hide yes)
			(effects
				(font
					(size 0.7874 0.5842)
					(thickness 0.1524)
				)
			)
		)
		(property "Device Type" "CAPACITOR-G105-0B104-CK,0.1UF,A"
			(at 0.0508 1.127506 270)
			(unlocked yes)
			(layer "F.Fab")
			(hide yes)
			(effects
				(font
					(size 0.7874 0.5842)
					(thickness 0.1524)
				)
			)
		)
		(property "User Part Number" "PARTNUM*"
			(at 0.1016 4.023106 270)
			(unlocked yes)
			(layer "Cmts.User")
			(hide yes)
			(effects
				(font
					(size 0.7874 0.5842)
					(thickness 0.1524)
				)
			)
		)
		(property "Tolerance" "TOL*"
			(at 0.0762 3.032506 270)
			(unlocked yes)
			(layer "Cmts.User")
			(hide yes)
			(effects
				(font
					(size 0.7874 0.5842)
					(thickness 0.1524)
				)
			)
		)
		(duplicate_pad_numbers_are_jumpers no)
		(fp_line
			(start -1.143 0.5588)
			(end 1.143 0.5588)
			(stroke
				(width 0.1)
				(type default)
			)
			(layer "F.SilkS")
		)
		(fp_line
			(start 1.143 0.5588)
			(end 1.143 -0.5588)
			(stroke
				(width 0.1)
				(type default)
			)
			(layer "F.SilkS")
		)
		(fp_line
			(start -1.143 -0.5588)
			(end -1.143 0.5588)
			(stroke
				(width 0.1)
				(type default)
			)
			(layer "F.SilkS")
		)
		(fp_line
			(start 1.143 -0.5588)
			(end -1.143 -0.5588)
			(stroke
				(width 0.1)
				(type default)
			)
			(layer "F.SilkS")
		)
		(fp_rect
			(start -1.143 -0.5588)
			(end 1.143 0.5588)
			(stroke
				(width 0)
				(type default)
			)
			(fill no)
			(layer "F.CrtYd")
		)
		(fp_line
			(start -0.508 0.3048)
			(end 0.508 0.3048)
			(stroke
				(width 0.1)
				(type default)
			)
			(layer "F.Fab")
		)
		(fp_line
			(start 0.508 0.3048)
			(end 0.508 -0.3048)
			(stroke
				(width 0.1)
				(type default)
			)
			(layer "F.Fab")
		)
		(fp_line
			(start -0.508 -0.3048)
			(end -0.508 0.3048)
			(stroke
				(width 0.1)
				(type default)
			)
			(layer "F.Fab")
		)
		(fp_line
			(start 0.508 -0.3048)
			(end -0.508 -0.3048)
			(stroke
				(width 0.1)
				(type default)
			)
			(layer "F.Fab")
		)
		(pad "1" smd rect
			(at -0.5334 0 270)
			(size 0.7112 0.6096)
			(layers "F.Cu" "F.Mask" "F.Paste")
			(net "XP3R3V_FPGA")
		)
		(pad "2" smd rect
			(at 0.5334 0 270)
			(size 0.7112 0.6096)
			(layers "F.Cu" "F.Mask" "F.Paste")
			(net "SG")
		)
		(zone
			(layer "F.Cu")
			(hatch none 0.5)
			(connect_pads
				(clearance 0)
			)
			(min_thickness 0.25)
			(keepout
				(tracks allowed)
				(vias not_allowed)
				(pads allowed)
				(copperpour not_allowed)
				(footprints allowed)
			)
			(placement
				(enabled no)
				(sheetname "")
			)
			(fill
				(thermal_gap 0.5)
				(thermal_bridge_width 0.5)
				(island_removal_mode 0)
			)
			(polygon
				(pts
					(xy 16.5608 -57.2262) (xy 15.9512 -57.2262) (xy 15.9512 -57.0738) (xy 16.5608 -57.0738)
				)
			)
		)
	)
	(footprint ""
		(layer "F.Cu")
		(at 80.772 -58.3946 180)
		(property "Reference" "R78"
			(at 10.668 19.39163 0)
			(unlocked yes)
			(layer "F.SilkS")
			(effects
				(font
					(size 0.7874 0.5842)
					(thickness 0.1524)
				)
			)
		)
		(property "Value" "VAL*"
			(at 0.02032 2.13233 180)
			(unlocked yes)
			(layer "F.Fab")
			(hide yes)
			(effects
				(font
					(size 0.7874 0.5842)
					(thickness 0.1524)
				)
			)
		)
		(property "Tolerance" "TOL*"
			(at 0.044704 3.05435 180)
			(unlocked yes)
			(layer "Cmts.User")
			(hide yes)
			(effects
				(font
					(size 0.7874 0.5842)
					(thickness 0.1524)
				)
			)
		)
		(property "User Part Number" "PARTNUM*"
			(at 0.02032 4.024884 180)
			(unlocked yes)
			(layer "Cmts.User")
			(hide yes)
			(effects
				(font
					(size 0.7874 0.5842)
					(thickness 0.1524)
				)
			)
		)
		(property "Device Type" "RESISTOR-G155-133R0-01,33OHM,1%"
			(at 0.008382 1.210564 180)
			(unlocked yes)
			(layer "F.Fab")
			(hide yes)
			(effects
				(font
					(size 0.7874 0.5842)
					(thickness 0.1524)
				)
			)
		)
		(duplicate_pad_numbers_are_jumpers no)
		(fp_line
			(start 1.143 0.5588)
			(end 1.143 -0.5588)
			(stroke
				(width 0.1)
				(type default)
			)
			(layer "F.SilkS")
		)
		(fp_line
			(start 1.143 -0.5588)
			(end -1.143 -0.5588)
			(stroke
				(width 0.1)
				(type default)
			)
			(layer "F.SilkS")
		)
		(fp_line
			(start -1.143 0.5588)
			(end 1.143 0.5588)
			(stroke
				(width 0.1)
				(type default)
			)
			(layer "F.SilkS")
		)
		(fp_line
			(start -1.143 -0.5588)
			(end -1.143 0.5588)
			(stroke
				(width 0.1)
				(type default)
			)
			(layer "F.SilkS")
		)
		(fp_rect
			(start 1.143 -0.5588)
			(end -1.143 0.5588)
			(stroke
				(width 0)
				(type default)
			)
			(fill no)
			(layer "F.CrtYd")
		)
		(fp_line
			(start 0.508 0.3048)
			(end 0.508 -0.3048)
			(stroke
				(width 0.1)
				(type default)
			)
			(layer "F.Fab")
		)
		(fp_line
			(start 0.508 -0.3048)
			(end -0.508 -0.3048)
			(stroke
				(width 0.1)
				(type default)
			)
			(layer "F.Fab")
		)
		(fp_line
			(start -0.508 0.3048)
			(end 0.508 0.3048)
			(stroke
				(width 0.1)
				(type default)
			)
			(layer "F.Fab")
		)
		(fp_line
			(start -0.508 -0.3048)
			(end -0.508 0.3048)
			(stroke
				(width 0.1)
				(type default)
			)
			(layer "F.Fab")
		)
		(pad "1" smd rect
			(at -0.5334 0 180)
			(size 0.7112 0.6096)
			(layers "F.Cu" "F.Mask" "F.Paste")
			(net "R_BNO080_RST_N")
		)
		(pad "2" smd rect
			(at 0.5334 0 180)
			(size 0.7112 0.6096)
			(layers "F.Cu" "F.Mask" "F.Paste")
			(net "FPGA_OUT_BNO080_RST_N")
		)
		(zone
			(layer "F.Cu")
			(hatch none 0.5)
			(connect_pads
				(clearance 0)
			)
			(min_thickness 0.25)
			(keepout
				(tracks allowed)
				(vias not_allowed)
				(pads allowed)
				(copperpour not_allowed)
				(footprints allowed)
			)
			(placement
				(enabled no)
				(sheetname "")
			)
			(fill
				(thermal_gap 0.5)
				(thermal_bridge_width 0.5)
				(island_removal_mode 0)
			)
			(polygon
				(pts
					(xy 80.6958 -58.0898) (xy 80.8482 -58.0898) (xy 80.8482 -58.6994) (xy 80.6958 -58.6994)
				)
			)
		)
	)
	(footprint ""
		(layer "F.Cu")
		(at 133.096 -31.496)
		(property "Reference" "C173"
			(at 4.572 0.29337 0)
			(unlocked yes)
			(layer "F.SilkS")
			(effects
				(font
					(size 0.7874 0.5842)
					(thickness 0.1524)
				)
			)
		)
		(property "Value" "VAL*"
			(at 0.0762 3.134106 0)
			(unlocked yes)
			(layer "F.Fab")
			(hide yes)
			(effects
				(font
					(size 0.7874 0.5842)
					(thickness 0.1524)
				)
			)
		)
		(property "Tolerance" "TOL*"
			(at 0.0762 4.048506 0)
			(unlocked yes)
			(layer "Cmts.User")
			(hide yes)
			(effects
				(font
					(size 0.7874 0.5842)
					(thickness 0.1524)
				)
			)
		)
		(property "User Part Number" "PARTNUM*"
			(at 0.1016 5.013706 0)
			(unlocked yes)
			(layer "Cmts.User")
			(hide yes)
			(effects
				(font
					(size 0.7874 0.5842)
					(thickness 0.1524)
				)
			)
		)
		(property "Device Type" "CAPACITOR-G107-0F476-AM,47UF,2A"
			(at 0.0508 2.194306 0)
			(unlocked yes)
			(layer "F.Fab")
			(hide yes)
			(effects
				(font
					(size 0.7874 0.5842)
					(thickness 0.1524)
				)
			)
		)
		(duplicate_pad_numbers_are_jumpers no)
		(fp_line
			(start -1.5748 -0.9398)
			(end -1.5748 0.9398)
			(stroke
				(width 0.1)
				(type default)
			)
			(layer "F.SilkS")
		)
		(fp_line
			(start -1.5748 0.9398)
			(end 1.5748 0.9398)
			(stroke
				(width 0.1)
				(type default)
			)
			(layer "F.SilkS")
		)
		(fp_line
			(start 1.5748 -0.9398)
			(end -1.5748 -0.9398)
			(stroke
				(width 0.1)
				(type default)
			)
			(layer "F.SilkS")
		)
		(fp_line
			(start 1.5748 0.9398)
			(end 1.5748 -0.9398)
			(stroke
				(width 0.1)
				(type default)
			)
			(layer "F.SilkS")
		)
		(fp_rect
			(start 1.5748 -0.9398)
			(end -1.5748 0.9398)
			(stroke
				(width 0)
				(type default)
			)
			(fill no)
			(layer "F.CrtYd")
		)
		(fp_line
			(start -1.016 -0.635)
			(end -1.016 0.635)
			(stroke
				(width 0.1)
				(type default)
			)
			(layer "F.Fab")
		)
		(fp_line
			(start -1.016 0.635)
			(end 1.016 0.635)
			(stroke
				(width 0.1)
				(type default)
			)
			(layer "F.Fab")
		)
		(fp_line
			(start 1.016 -0.635)
			(end -1.016 -0.635)
			(stroke
				(width 0.1)
				(type default)
			)
			(layer "F.Fab")
		)
		(fp_line
			(start 1.016 0.635)
			(end 1.016 -0.635)
			(stroke
				(width 0.1)
				(type default)
			)
			(layer "F.Fab")
		)
		(pad "1" smd rect
			(at -0.8382 0)
			(size 0.9652 1.3716)
			(layers "F.Cu" "F.Mask" "F.Paste")
			(net "XP1R0V_FPGA_VCCINT")
		)
		(pad "2" smd rect
			(at 0.8382 0)
			(size 0.9652 1.3716)
			(layers "F.Cu" "F.Mask" "F.Paste")
			(net "SG")
		)
		(zone
			(layer "F.Cu")
			(hatch none 0.5)
			(connect_pads
				(clearance 0)
			)
			(min_thickness 0.25)
			(keepout
				(tracks allowed)
				(vias not_allowed)
				(pads allowed)
				(copperpour not_allowed)
				(footprints allowed)
			)
			(placement
				(enabled no)
				(sheetname "")
			)
			(fill
				(thermal_gap 0.5)
				(thermal_bridge_width 0.5)
				(island_removal_mode 0)
			)
			(polygon
				(pts
					(xy 133.3246 -32.131) (xy 132.8674 -32.131) (xy 132.8674 -30.861) (xy 133.3246 -30.861)
				)
			)
		)
	)
	(footprint ""
		(layer "F.Cu")
		(at 31.75 -95.25 180)
		(property "Reference" "R455"
			(at -2.667 -1.69037 0)
			(unlocked yes)
			(layer "F.SilkS")
			(effects
				(font
					(size 0.7874 0.5842)
					(thickness 0.1524)
				)
			)
		)
		(property "Value" "VAL*"
			(at 0.02032 2.13233 180)
			(unlocked yes)
			(layer "F.Fab")
			(hide yes)
			(effects
				(font
					(size 0.7874 0.5842)
					(thickness 0.1524)
				)
			)
		)
		(property "Tolerance" "TOL*"
			(at 0.044704 3.05435 180)
			(unlocked yes)
			(layer "Cmts.User")
			(hide yes)
			(effects
				(font
					(size 0.7874 0.5842)
					(thickness 0.1524)
				)
			)
		)
		(property "User Part Number" "PARTNUM*"
			(at 0.02032 4.024884 180)
			(unlocked yes)
			(layer "Cmts.User")
			(hide yes)
			(effects
				(font
					(size 0.7874 0.5842)
					(thickness 0.1524)
				)
			)
		)
		(property "Device Type" "RESISTOR-G155-11004-01,1MOHM,1%"
			(at 0.008382 1.210564 180)
			(unlocked yes)
			(layer "F.Fab")
			(hide yes)
			(effects
				(font
					(size 0.7874 0.5842)
					(thickness 0.1524)
				)
			)
		)
		(duplicate_pad_numbers_are_jumpers no)
		(fp_line
			(start 1.143 0.5588)
			(end 1.143 -0.5588)
			(stroke
				(width 0.1)
				(type default)
			)
			(layer "F.SilkS")
		)
		(fp_line
			(start 1.143 -0.5588)
			(end -1.143 -0.5588)
			(stroke
				(width 0.1)
				(type default)
			)
			(layer "F.SilkS")
		)
		(fp_line
			(start -1.143 0.5588)
			(end 1.143 0.5588)
			(stroke
				(width 0.1)
				(type default)
			)
			(layer "F.SilkS")
		)
		(fp_line
			(start -1.143 -0.5588)
			(end -1.143 0.5588)
			(stroke
				(width 0.1)
				(type default)
			)
			(layer "F.SilkS")
		)
		(fp_poly
			(pts
				(xy -1.143 0.5588) (xy 1.143 0.5588) (xy 1.143 -0.5588) (xy -1.143 -0.5588)
			)
			(stroke
				(width 0)
				(type default)
			)
			(fill no)
			(layer "F.CrtYd")
		)
		(fp_line
			(start 0.508 0.3048)
			(end 0.508 -0.3048)
			(stroke
				(width 0.1)
				(type default)
			)
			(layer "F.Fab")
		)
		(fp_line
			(start 0.508 -0.3048)
			(end -0.508 -0.3048)
			(stroke
				(width 0.1)
				(type default)
			)
			(layer "F.Fab")
		)
		(fp_line
			(start -0.508 0.3048)
			(end 0.508 0.3048)
			(stroke
				(width 0.1)
				(type default)
			)
			(layer "F.Fab")
		)
		(fp_line
			(start -0.508 -0.3048)
			(end -0.508 0.3048)
			(stroke
				(width 0.1)
				(type default)
			)
			(layer "F.Fab")
		)
		(pad "1" smd rect
			(at -0.5334 0 180)
			(size 0.7112 0.6096)
			(layers "F.Cu" "F.Mask" "F.Paste")
			(net "UNNAMED_524_CAPACITOR_I7_2")
		)
		(pad "2" smd rect
			(at 0.5334 0 180)
			(size 0.7112 0.6096)
			(layers "F.Cu" "F.Mask" "F.Paste")
			(net "UNNAMED_524_CAPACITOR_I10_2")
		)
		(zone
			(layer "F.Cu")
			(hatch none 0.5)
			(connect_pads
				(clearance 0)
			)
			(min_thickness 0.25)
			(keepout
				(tracks allowed)
				(vias not_allowed)
				(pads allowed)
				(copperpour not_allowed)
				(footprints allowed)
			)
			(placement
				(enabled no)
				(sheetname "")
			)
			(fill
				(thermal_gap 0.5)
				(thermal_bridge_width 0.5)
				(island_removal_mode 0)
			)
			(polygon
				(pts
					(xy 31.8262 -95.5548) (xy 31.6738 -95.5548) (xy 31.6738 -94.9452) (xy 31.8262 -94.9452)
				)
			)
		)
		(zone
			(layer "F.Cu")
			(hatch none 0.5)
			(connect_pads
				(clearance 0)
			)
			(min_thickness 0.25)
			(keepout
				(tracks not_allowed)
				(vias allowed)
				(pads allowed)
				(copperpour not_allowed)
				(footprints allowed)
			)
			(placement
				(enabled no)
				(sheetname "")
			)
			(fill
				(thermal_gap 0.5)
				(thermal_bridge_width 0.5)
				(island_removal_mode 0)
			)
			(polygon
				(pts
					(xy 31.8262 -95.5548) (xy 31.6738 -95.5548) (xy 31.6738 -94.9452) (xy 31.8262 -94.9452)
				)
			)
		)
	)
	(footprint ""
		(layer "F.Cu")
		(at 122.6312 -28.0162 90)
		(property "Reference" "TP194"
			(at -1.37795 -0.635 0)
			(unlocked yes)
			(layer "F.SilkS")
			(effects
				(font
					(size 0.635 0.4064)
					(thickness 0.1524)
				)
				(justify left)
			)
		)
		(property "Value" ""
			(at 0 0 90)
			(layer "F.Fab")
			(effects
				(font
					(size 1.27 1.27)
				)
			)
		)
		(property "Device Type" "TP_PIONT-TP010CT020B030_PTH-TPA"
			(at -1.341882 0.996696 90)
			(unlocked yes)
			(layer "F.Fab")
			(hide yes)
			(effects
				(font
					(size 0.7874 0.5842)
					(thickness 0.1524)
				)
				(justify left)
			)
		)
		(duplicate_pad_numbers_are_jumpers no)
		(fp_poly
			(pts
				(arc
					(start 0 0.889)
					(mid 0 -0.889)
					(end 0 0.889)
				)
			)
			(stroke
				(width 0)
				(type default)
			)
			(fill no)
			(layer "B.CrtYd")
		)
		(fp_poly
			(pts
				(arc
					(start 0 0.889)
					(mid 0 -0.889)
					(end 0 0.889)
				)
			)
			(stroke
				(width 0)
				(type default)
			)
			(fill no)
			(layer "F.CrtYd")
		)
		(pad "1" thru_hole circle
			(at 0 0 90)
			(size 0.508 0.508)
			(drill 0.254)
			(layers "*.Cu" "*.Mask")
			(remove_unused_layers no)
			(net "IO_L21N_35")
			(clearance 0.1016)
			(padstack
				(mode front_inner_back)
				(layer "Inner"
					(shape circle)
					(size 0.508 0.508)
					(clearance 0.1016)
				)
				(layer "B.Cu"
					(shape circle)
					(size 0.762 0.762)
					(clearance -0.0254)
				)
			)
		)
	)
)
